(kicad_pcb
	(version 20260206)
	(generator "pcbnew")
	(generator_version "10.0")
	(general
		(thickness 1.6)
		(legacy_teardrops no)
	)
	(paper "A4")
	(title_block
		(title "01162023_DA0F0TEBIF0_F0T_Expander_BD_F_brd_V02_OCP.brd")
		(comment 1 "Grand Teton / footprints 4117-4122 of 9728")
	)
	(layers
		(0 "F.Cu" signal "TOP")
		(4 "In1.Cu" signal "GND")
		(6 "In2.Cu" signal "VCC")
		(8 "In3.Cu" signal "VCC1")
		(10 "In4.Cu" signal "GND1")
		(12 "In5.Cu" signal "IN1")
		(14 "In6.Cu" signal "GND2")
		(16 "In7.Cu" signal "IN2")
		(18 "In8.Cu" signal "GND3")
		(20 "In9.Cu" signal "IN3")
		(22 "In10.Cu" signal "GND4")
		(24 "In11.Cu" signal "IN4")
		(26 "In12.Cu" signal "GND5")
		(28 "In13.Cu" signal "IN5")
		(30 "In14.Cu" signal "GND6")
		(32 "In15.Cu" signal "IN6")
		(34 "In16.Cu" signal "GND7")
		(2 "B.Cu" signal "BOTTOM")
		(9 "F.Adhes" user "F.Adhesive")
		(11 "B.Adhes" user "B.Adhesive")
		(13 "F.Paste" user "Package Geometry/Pastemask Top")
		(15 "B.Paste" user "Package Geometry/Pastemask Bottom")
		(5 "F.SilkS" user "Ref Des/Silkscreen Top")
		(7 "B.SilkS" user "Ref Des/Silkscreen Bottom")
		(1 "F.Mask" user "Board Geometry/Soldermask Top")
		(3 "B.Mask" user "Board Geometry/Soldermask Bottom")
		(17 "Dwgs.User" user "User.Drawings")
		(19 "Cmts.User" user "User.Comments")
		(21 "Eco1.User" user "User.Eco1")
		(23 "Eco2.User" user "User.Eco2")
		(25 "Edge.Cuts" user "Board Geometry/Outline")
		(27 "Margin" user)
		(31 "F.CrtYd" user "Package Geometry/Place Bound Top")
		(29 "B.CrtYd" user "Package Geometry/Place Bound Bottom")
		(35 "F.Fab" user "Ref Des/Assembly Top")
		(33 "B.Fab" user "Ref Des/Assembly Bottom")
	)
	(footprint ""
		(layer "F.Cu")
		(at 240.306606 -80.451706 180)
		(property "Reference" "R1002"
			(at 0 0 180)
			(layer "F.SilkS")
			(hide yes)
			(effects
				(font
					(size 1.27 1.27)
				)
			)
		)
		(property "Value" ""
			(at 0 0 180)
			(layer "F.Fab")
			(effects
				(font
					(size 1.27 1.27)
				)
			)
		)
		(duplicate_pad_numbers_are_jumpers no)
		(fp_line
			(start 0.7874 0.4064)
			(end -0.7874 0.4064)
			(stroke
				(width 0.1524)
				(type default)
			)
			(layer "F.SilkS")
		)
		(fp_line
			(start 0.7874 -0.4064)
			(end 0.7874 0.4064)
			(stroke
				(width 0.1524)
				(type default)
			)
			(layer "F.SilkS")
		)
		(fp_line
			(start -0.7874 0.4064)
			(end -0.7874 -0.4064)
			(stroke
				(width 0.1524)
				(type default)
			)
			(layer "F.SilkS")
		)
		(fp_line
			(start -0.7874 -0.4064)
			(end 0.7874 -0.4064)
			(stroke
				(width 0.1524)
				(type default)
			)
			(layer "F.SilkS")
		)
		(fp_line
			(start 0.67945 0.3048)
			(end 0.120396 0.3048)
			(stroke
				(width 0.1)
				(type default)
			)
			(layer "F.Fab")
		)
		(fp_line
			(start 0.67945 -0.3048)
			(end 0.67945 0.3048)
			(stroke
				(width 0.1)
				(type default)
			)
			(layer "F.Fab")
		)
		(fp_line
			(start 0.12065 -0.2794)
			(end 0.12065 -0.3048)
			(stroke
				(width 0.1)
				(type default)
			)
			(layer "F.Fab")
		)
		(fp_line
			(start 0.12065 -0.3048)
			(end 0.67945 -0.3048)
			(stroke
				(width 0.1)
				(type default)
			)
			(layer "F.Fab")
		)
		(fp_line
			(start 0.120396 0.3048)
			(end 0.120396 0.2794)
			(stroke
				(width 0.1)
				(type default)
			)
			(layer "F.Fab")
		)
		(fp_line
			(start 0.120396 0.2794)
			(end -0.12065 0.2794)
			(stroke
				(width 0.1)
				(type default)
			)
			(layer "F.Fab")
		)
		(fp_line
			(start -0.12065 0.3048)
			(end -0.67945 0.3048)
			(stroke
				(width 0.1)
				(type default)
			)
			(layer "F.Fab")
		)
		(fp_line
			(start -0.12065 0.2794)
			(end -0.12065 0.3048)
			(stroke
				(width 0.1)
				(type default)
			)
			(layer "F.Fab")
		)
		(fp_line
			(start -0.12065 -0.2794)
			(end 0.12065 -0.2794)
			(stroke
				(width 0.1)
				(type default)
			)
			(layer "F.Fab")
		)
		(fp_line
			(start -0.12065 -0.305054)
			(end -0.12065 -0.2794)
			(stroke
				(width 0.1)
				(type default)
			)
			(layer "F.Fab")
		)
		(fp_line
			(start -0.67945 0.3048)
			(end -0.67945 -0.305054)
			(stroke
				(width 0.1)
				(type default)
			)
			(layer "F.Fab")
		)
		(fp_line
			(start -0.67945 -0.305054)
			(end -0.12065 -0.305054)
			(stroke
				(width 0.1)
				(type default)
			)
			(layer "F.Fab")
		)
		(pad "1" smd circle
			(at -0.40005 0 180)
			(size 0 0)
			(layers "F.Cu" "F.Mask" "F.Paste")
			(net "PEX_USB2_SEL_CONN")
		)
		(pad "2" smd circle
			(at 0.40005 0 180)
			(size 0 0)
			(layers "F.Cu" "F.Mask" "F.Paste")
			(net "P3V3_AUX")
		)
	)
	(footprint ""
		(layer "F.Cu")
		(at 363.474 -205.867)
		(property "Reference" "R4605"
			(at 0 0 0)
			(layer "F.SilkS")
			(hide yes)
			(effects
				(font
					(size 1.27 1.27)
				)
			)
		)
		(property "Value" ""
			(at 0 0 0)
			(layer "F.Fab")
			(effects
				(font
					(size 1.27 1.27)
				)
			)
		)
		(duplicate_pad_numbers_are_jumpers no)
		(fp_line
			(start -0.7874 -0.4064)
			(end 0.7874 -0.4064)
			(stroke
				(width 0.1524)
				(type default)
			)
			(layer "F.SilkS")
		)
		(fp_line
			(start -0.7874 0.4064)
			(end -0.7874 -0.4064)
			(stroke
				(width 0.1524)
				(type default)
			)
			(layer "F.SilkS")
		)
		(fp_line
			(start 0.7874 -0.4064)
			(end 0.7874 0.4064)
			(stroke
				(width 0.1524)
				(type default)
			)
			(layer "F.SilkS")
		)
		(fp_line
			(start 0.7874 0.4064)
			(end -0.7874 0.4064)
			(stroke
				(width 0.1524)
				(type default)
			)
			(layer "F.SilkS")
		)
		(fp_line
			(start -0.67945 -0.305054)
			(end -0.12065 -0.305054)
			(stroke
				(width 0.1)
				(type default)
			)
			(layer "F.Fab")
		)
		(fp_line
			(start -0.67945 0.3048)
			(end -0.67945 -0.305054)
			(stroke
				(width 0.1)
				(type default)
			)
			(layer "F.Fab")
		)
		(fp_line
			(start -0.12065 -0.305054)
			(end -0.12065 -0.2794)
			(stroke
				(width 0.1)
				(type default)
			)
			(layer "F.Fab")
		)
		(fp_line
			(start -0.12065 -0.2794)
			(end 0.12065 -0.2794)
			(stroke
				(width 0.1)
				(type default)
			)
			(layer "F.Fab")
		)
		(fp_line
			(start -0.12065 0.2794)
			(end -0.12065 0.3048)
			(stroke
				(width 0.1)
				(type default)
			)
			(layer "F.Fab")
		)
		(fp_line
			(start -0.12065 0.3048)
			(end -0.67945 0.3048)
			(stroke
				(width 0.1)
				(type default)
			)
			(layer "F.Fab")
		)
		(fp_line
			(start 0.120396 0.2794)
			(end -0.12065 0.2794)
			(stroke
				(width 0.1)
				(type default)
			)
			(layer "F.Fab")
		)
		(fp_line
			(start 0.120396 0.3048)
			(end 0.120396 0.2794)
			(stroke
				(width 0.1)
				(type default)
			)
			(layer "F.Fab")
		)
		(fp_line
			(start 0.12065 -0.3048)
			(end 0.67945 -0.3048)
			(stroke
				(width 0.1)
				(type default)
			)
			(layer "F.Fab")
		)
		(fp_line
			(start 0.12065 -0.2794)
			(end 0.12065 -0.3048)
			(stroke
				(width 0.1)
				(type default)
			)
			(layer "F.Fab")
		)
		(fp_line
			(start 0.67945 -0.3048)
			(end 0.67945 0.3048)
			(stroke
				(width 0.1)
				(type default)
			)
			(layer "F.Fab")
		)
		(fp_line
			(start 0.67945 0.3048)
			(end 0.120396 0.3048)
			(stroke
				(width 0.1)
				(type default)
			)
			(layer "F.Fab")
		)
		(pad "1" smd circle
			(at -0.40005 0)
			(size 0 0)
			(layers "F.Cu" "F.Mask" "F.Paste")
			(net "P3V3_AUX")
		)
		(pad "2" smd circle
			(at 0.40005 0)
			(size 0 0)
			(layers "F.Cu" "F.Mask" "F.Paste")
			(net "RST_PEX_SSD1_PERST_R_N")
		)
	)
	(footprint ""
		(layer "F.Cu")
		(at 368.875564 -69.47916 180)
		(property "Reference" "PU115"
			(at -1.813306 4.13004 90)
			(unlocked yes)
			(layer "F.SilkS")
			(effects
				(font
					(size 0.7874 0.5842)
					(thickness 0.1524)
				)
			)
		)
		(property "Value" ""
			(at 0 0 180)
			(layer "F.Fab")
			(effects
				(font
					(size 1.27 1.27)
				)
			)
		)
		(duplicate_pad_numbers_are_jumpers no)
		(fp_line
			(start 1.239774 1.495298)
			(end -1.239774 1.495298)
			(stroke
				(width 0.1524)
				(type default)
			)
			(layer "F.SilkS")
		)
		(fp_line
			(start 1.239774 -1.495298)
			(end 1.239774 1.495298)
			(stroke
				(width 0.1524)
				(type default)
			)
			(layer "F.SilkS")
		)
		(fp_line
			(start -1.239774 1.495298)
			(end -1.239774 -1.495298)
			(stroke
				(width 0.1524)
				(type default)
			)
			(layer "F.SilkS")
		)
		(fp_line
			(start -1.239774 -1.495298)
			(end 1.239774 -1.495298)
			(stroke
				(width 0.1524)
				(type default)
			)
			(layer "F.SilkS")
		)
		(fp_poly
			(pts
				(xy -1.746758 -2.302256) (xy -2.465324 -1.58369) (xy -1.387602 -1.224534)
			)
			(stroke
				(width 0)
				(type default)
			)
			(fill yes)
			(layer "F.SilkS")
		)
		(fp_line
			(start 0.8001 1.050036)
			(end -0.8001 1.050036)
			(stroke
				(width 0.1)
				(type default)
			)
			(layer "F.Fab")
		)
		(fp_line
			(start 0.8001 -1.050036)
			(end 0.8001 1.050036)
			(stroke
				(width 0.1)
				(type default)
			)
			(layer "F.Fab")
		)
		(fp_line
			(start -0.8001 1.050036)
			(end -0.8001 -1.050036)
			(stroke
				(width 0.1)
				(type default)
			)
			(layer "F.Fab")
		)
		(fp_line
			(start -0.8001 -1.050036)
			(end 0.8001 -1.050036)
			(stroke
				(width 0.1)
				(type default)
			)
			(layer "F.Fab")
		)
		(fp_poly
			(pts
				(xy -2.458974 -0.508) (xy -2.458974 0.508) (xy -1.442974 0)
			)
			(stroke
				(width 0)
				(type default)
			)
			(fill yes)
			(layer "F.Fab")
		)
		(pad "1_2" smd circle
			(at -0.374904 0 270)
			(size 0 0)
			(layers "F.Cu" "F.Mask" "F.Paste")
			(net "P12V_AUX")
		)
		(pad "3" smd rect
			(at -0.499872 0.999998 180)
			(size 0.254 0.7112)
			(layers "F.Cu" "F.Mask" "F.Paste")
			(net "GND")
		)
		(pad "4" smd rect
			(at 0 0.999998 180)
			(size 0.254 0.7112)
			(layers "F.Cu" "F.Mask" "F.Paste")
			(net "P12V_SSD12_CO_ILIMIT")
		)
		(pad "5" smd rect
			(at 0.499872 0.999998 180)
			(size 0.254 0.7112)
			(layers "F.Cu" "F.Mask" "F.Paste")
			(net "P12V_SSD12_CO_MODE")
		)
		(pad "6_7" smd circle
			(at 0.374904 0 90)
			(size 0 0)
			(layers "F.Cu" "F.Mask" "F.Paste")
			(net "P12V_SSD12_R")
		)
		(pad "8" smd rect
			(at 0.499872 -0.999998 180)
			(size 0.254 0.7112)
			(layers "F.Cu" "F.Mask" "F.Paste")
			(net "P12V_SSD12_CO_GATE")
		)
		(pad "9" smd rect
			(at 0 -0.999998 180)
			(size 0.254 0.7112)
			(layers "F.Cu" "F.Mask" "F.Paste")
			(net "P12V_SSD12_CO_EN")
		)
		(pad "10" smd rect
			(at -0.499872 -0.999998 180)
			(size 0.254 0.7112)
			(layers "F.Cu" "F.Mask" "F.Paste")
			(net "P12V_SSD12_CO_DV_DT")
		)
	)
	(footprint ""
		(layer "F.Cu")
		(at 226.029266 -104.328722 90)
		(property "Reference" "PC340"
			(at 0 0 90)
			(layer "F.SilkS")
			(hide yes)
			(effects
				(font
					(size 1.27 1.27)
				)
			)
		)
		(property "Value" ""
			(at 0 0 90)
			(layer "F.Fab")
			(effects
				(font
					(size 1.27 1.27)
				)
			)
		)
		(duplicate_pad_numbers_are_jumpers no)
		(fp_line
			(start 0.7874 -0.4064)
			(end 0.7874 0.4064)
			(stroke
				(width 0.1524)
				(type default)
			)
			(layer "F.SilkS")
		)
		(fp_line
			(start -0.7874 -0.4064)
			(end 0.7874 -0.4064)
			(stroke
				(width 0.1524)
				(type default)
			)
			(layer "F.SilkS")
		)
		(fp_line
			(start 0.7874 0.4064)
			(end -0.7874 0.4064)
			(stroke
				(width 0.1524)
				(type default)
			)
			(layer "F.SilkS")
		)
		(fp_line
			(start -0.7874 0.4064)
			(end -0.7874 -0.4064)
			(stroke
				(width 0.1524)
				(type default)
			)
			(layer "F.SilkS")
		)
		(fp_line
			(start -0.12065 -0.305054)
			(end -0.12065 -0.2794)
			(stroke
				(width 0.1)
				(type default)
			)
			(layer "F.Fab")
		)
		(fp_line
			(start -0.67945 -0.305054)
			(end -0.12065 -0.305054)
			(stroke
				(width 0.1)
				(type default)
			)
			(layer "F.Fab")
		)
		(fp_line
			(start 0.67945 -0.3048)
			(end 0.67945 0.3048)
			(stroke
				(width 0.1)
				(type default)
			)
			(layer "F.Fab")
		)
		(fp_line
			(start 0.12065 -0.3048)
			(end 0.67945 -0.3048)
			(stroke
				(width 0.1)
				(type default)
			)
			(layer "F.Fab")
		)
		(fp_line
			(start 0.12065 -0.2794)
			(end 0.12065 -0.3048)
			(stroke
				(width 0.1)
				(type default)
			)
			(layer "F.Fab")
		)
		(fp_line
			(start -0.12065 -0.2794)
			(end 0.12065 -0.2794)
			(stroke
				(width 0.1)
				(type default)
			)
			(layer "F.Fab")
		)
		(fp_line
			(start 0.120396 0.2794)
			(end -0.12065 0.2794)
			(stroke
				(width 0.1)
				(type default)
			)
			(layer "F.Fab")
		)
		(fp_line
			(start -0.12065 0.2794)
			(end -0.12065 0.3048)
			(stroke
				(width 0.1)
				(type default)
			)
			(layer "F.Fab")
		)
		(fp_line
			(start 0.67945 0.3048)
			(end 0.120396 0.3048)
			(stroke
				(width 0.1)
				(type default)
			)
			(layer "F.Fab")
		)
		(fp_line
			(start 0.120396 0.3048)
			(end 0.120396 0.2794)
			(stroke
				(width 0.1)
				(type default)
			)
			(layer "F.Fab")
		)
		(fp_line
			(start -0.12065 0.3048)
			(end -0.67945 0.3048)
			(stroke
				(width 0.1)
				(type default)
			)
			(layer "F.Fab")
		)
		(fp_line
			(start -0.67945 0.3048)
			(end -0.67945 -0.305054)
			(stroke
				(width 0.1)
				(type default)
			)
			(layer "F.Fab")
		)
		(pad "1" smd circle
			(at -0.40005 0 90)
			(size 0 0)
			(layers "F.Cu" "F.Mask" "F.Paste")
			(net "P12V_AUX")
		)
		(pad "2" smd circle
			(at 0.40005 0 90)
			(size 0 0)
			(layers "F.Cu" "F.Mask" "F.Paste")
			(net "GND")
		)
	)
	(footprint ""
		(layer "F.Cu")
		(at 144.53108 -188.752988)
		(property "Reference" "R6666"
			(at 0 0 0)
			(layer "F.SilkS")
			(hide yes)
			(effects
				(font
					(size 1.27 1.27)
				)
			)
		)
		(property "Value" ""
			(at 0 0 0)
			(layer "F.Fab")
			(effects
				(font
					(size 1.27 1.27)
				)
			)
		)
		(duplicate_pad_numbers_are_jumpers no)
		(fp_line
			(start -0.7874 -0.4064)
			(end 0.7874 -0.4064)
			(stroke
				(width 0.1524)
				(type default)
			)
			(layer "F.SilkS")
		)
		(fp_line
			(start -0.7874 0.4064)
			(end -0.7874 -0.4064)
			(stroke
				(width 0.1524)
				(type default)
			)
			(layer "F.SilkS")
		)
		(fp_line
			(start 0.7874 -0.4064)
			(end 0.7874 0.4064)
			(stroke
				(width 0.1524)
				(type default)
			)
			(layer "F.SilkS")
		)
		(fp_line
			(start 0.7874 0.4064)
			(end -0.7874 0.4064)
			(stroke
				(width 0.1524)
				(type default)
			)
			(layer "F.SilkS")
		)
		(fp_line
			(start -0.67945 -0.305054)
			(end -0.12065 -0.305054)
			(stroke
				(width 0.1)
				(type default)
			)
			(layer "F.Fab")
		)
		(fp_line
			(start -0.67945 0.3048)
			(end -0.67945 -0.305054)
			(stroke
				(width 0.1)
				(type default)
			)
			(layer "F.Fab")
		)
		(fp_line
			(start -0.12065 -0.305054)
			(end -0.12065 -0.2794)
			(stroke
				(width 0.1)
				(type default)
			)
			(layer "F.Fab")
		)
		(fp_line
			(start -0.12065 -0.2794)
			(end 0.12065 -0.2794)
			(stroke
				(width 0.1)
				(type default)
			)
			(layer "F.Fab")
		)
		(fp_line
			(start -0.12065 0.2794)
			(end -0.12065 0.3048)
			(stroke
				(width 0.1)
				(type default)
			)
			(layer "F.Fab")
		)
		(fp_line
			(start -0.12065 0.3048)
			(end -0.67945 0.3048)
			(stroke
				(width 0.1)
				(type default)
			)
			(layer "F.Fab")
		)
		(fp_line
			(start 0.120396 0.2794)
			(end -0.12065 0.2794)
			(stroke
				(width 0.1)
				(type default)
			)
			(layer "F.Fab")
		)
		(fp_line
			(start 0.120396 0.3048)
			(end 0.120396 0.2794)
			(stroke
				(width 0.1)
				(type default)
			)
			(layer "F.Fab")
		)
		(fp_line
			(start 0.12065 -0.3048)
			(end 0.67945 -0.3048)
			(stroke
				(width 0.1)
				(type default)
			)
			(layer "F.Fab")
		)
		(fp_line
			(start 0.12065 -0.2794)
			(end 0.12065 -0.3048)
			(stroke
				(width 0.1)
				(type default)
			)
			(layer "F.Fab")
		)
		(fp_line
			(start 0.67945 -0.3048)
			(end 0.67945 0.3048)
			(stroke
				(width 0.1)
				(type default)
			)
			(layer "F.Fab")
		)
		(fp_line
			(start 0.67945 0.3048)
			(end 0.120396 0.3048)
			(stroke
				(width 0.1)
				(type default)
			)
			(layer "F.Fab")
		)
		(pad "1" smd circle
			(at -0.40005 0)
			(size 0 0)
			(layers "F.Cu" "F.Mask" "F.Paste")
			(net "NIC5_CLK_EN_BUF_N")
		)
		(pad "2" smd circle
			(at 0.40005 0)
			(size 0 0)
			(layers "F.Cu" "F.Mask" "F.Paste")
			(net "NIC5_CLK_EN_BUF_R_N")
		)
	)
	(footprint ""
		(layer "F.Cu")
		(at 268.53515 -83.351624 180)
		(property "Reference" "R1072"
			(at 0 0 180)
			(layer "F.SilkS")
			(hide yes)
			(effects
				(font
					(size 1.27 1.27)
				)
			)
		)
		(property "Value" ""
			(at 0 0 180)
			(layer "F.Fab")
			(effects
				(font
					(size 1.27 1.27)
				)
			)
		)
		(duplicate_pad_numbers_are_jumpers no)
		(fp_line
			(start -0.7874 -0.4064)
			(end 0.7874 -0.4064)
			(stroke
				(width 0.1524)
				(type default)
			)
			(layer "F.SilkS")
		)
		(fp_line
			(start 0.67945 0.3048)
			(end 0.120396 0.3048)
			(stroke
				(width 0.1)
				(type default)
			)
			(layer "F.Fab")
		)
		(fp_line
			(start 0.67945 -0.3048)
			(end 0.67945 0.3048)
			(stroke
				(width 0.1)
				(type default)
			)
			(layer "F.Fab")
		)
		(fp_line
			(start 0.12065 -0.2794)
			(end 0.12065 -0.3048)
			(stroke
				(width 0.1)
				(type default)
			)
			(layer "F.Fab")
		)
		(fp_line
			(start 0.12065 -0.3048)
			(end 0.67945 -0.3048)
			(stroke
				(width 0.1)
				(type default)
			)
			(layer "F.Fab")
		)
		(fp_line
			(start 0.120396 0.3048)
			(end 0.120396 0.2794)
			(stroke
				(width 0.1)
				(type default)
			)
			(layer "F.Fab")
		)
		(fp_line
			(start 0.120396 0.2794)
			(end -0.12065 0.2794)
			(stroke
				(width 0.1)
				(type default)
			)
			(layer "F.Fab")
		)
		(fp_line
			(start -0.12065 0.3048)
			(end -0.67945 0.3048)
			(stroke
				(width 0.1)
				(type default)
			)
			(layer "F.Fab")
		)
		(fp_line
			(start -0.12065 0.2794)
			(end -0.12065 0.3048)
			(stroke
				(width 0.1)
				(type default)
			)
			(layer "F.Fab")
		)
		(fp_line
			(start -0.12065 -0.2794)
			(end 0.12065 -0.2794)
			(stroke
				(width 0.1)
				(type default)
			)
			(layer "F.Fab")
		)
		(fp_line
			(start -0.12065 -0.305054)
			(end -0.12065 -0.2794)
			(stroke
				(width 0.1)
				(type default)
			)
			(layer "F.Fab")
		)
		(fp_line
			(start -0.67945 0.3048)
			(end -0.67945 -0.305054)
			(stroke
				(width 0.1)
				(type default)
			)
			(layer "F.Fab")
		)
		(fp_line
			(start -0.67945 -0.305054)
			(end -0.12065 -0.305054)
			(stroke
				(width 0.1)
				(type default)
			)
			(layer "F.Fab")
		)
		(pad "1" smd circle
			(at -0.40005 0 180)
			(size 0 0)
			(layers "F.Cu" "F.Mask" "F.Paste")
			(net "CLK_100M_CK440Q_0_DB2000QL_R_DN")
		)
		(pad "2" smd circle
			(at 0.40005 0 180)
			(size 0 0)
			(layers "F.Cu" "F.Mask" "F.Paste")
			(net "CLK_100M_CK440Q_0_DB2000QL_DN")
		)
	)
)
